( ConstraintFile "p5v_stby"
	( constraintHeader
		( objectKey
			( logical )
		)
		( version
			( 16.5 )
		)
		( revisionNumber
			( logicalViewRevNum 2 )
			( physicalViewRevNum 0 )
			( otherViewRevNum 0 )
		)
		( contents
			( dictionaryExtensions )
			( worksheetCustomizations )
			( electricalConstraints )
			( netClasses )
			( properties )
		)
		( precision
			( units mil )
			( numberOfDecimalPlaces 2 )
		)
	)
	( DictionaryExtensions
		( Attribute
			( Name "MATERIAL" )
			( Description " " )
			( Value
				( DataType ( dString ) )
				( Status  sProperty  sPackage )
			)
			( Objects
				( ValidObjects  oGate  oGateDefn  oBlock  oPart  oDesign  oSystem  oPartDefn )
				( NoInherit
					( oGate oPin )
				)
			)
			( Analysis
			)
		)
		( Attribute
			( Name "TOLERANCE" )
			( Description " " )
			( Value
				( DataType ( dString ) )
				( Status  sProperty  sPackage )
			)
			( Objects
				( ValidObjects  oGate  oGateDefn  oBlock  oPart  oDesign  oSystem  oPartDefn )
				( NoInherit
					( oGate oPin )
				)
			)
			( Analysis
			)
		)
		( Attribute
			( Name "WATTAGE" )
			( Description " " )
			( Value
				( DataType ( dString ) )
				( Status  sProperty  sPackage )
			)
			( Objects
				( ValidObjects  oGate  oGateDefn  oBlock  oPart  oDesign  oSystem  oPartDefn )
				( NoInherit
					( oGate oPin )
				)
			)
			( Analysis
			)
		)
		( Attribute
			( Name "CDS_LMAN_SYM_OUTLINE" )
			( Description " " )
			( Value
				( DataType ( dString ) )
				( Status  sProperty  sPackage )
			)
			( Objects
				( ValidObjects  oGate  oGateDefn  oBlock  oPart  oDesign  oSystem  oPartDefn )
				( NoInherit
					( oGate oPin )
				)
			)
			( Analysis
			)
		)
		( Attribute
			( Name "SEC_TYPE" )
			( Description " " )
			( Value
				( DataType ( dString ) )
				( Status  sProperty  sPackage )
			)
			( Objects
				( ValidObjects  oGate  oGateDefn  oBlock  oPart  oDesign  oSystem  oPartDefn )
				( NoInherit
					( oGate oPin )
				)
			)
			( Analysis
			)
		)
		( Attribute
			( Name "$sec" )
			( Description "" )
			( Value
				( DataType ( dString ) )
				( Status  sProperty )
			)
			( Objects
				( ValidObjects  oAll )
			)
			( Analysis
			)
		)
		( Attribute
			( Name "$location" )
			( Description "" )
			( Value
				( DataType ( dString ) )
				( Status  sProperty )
			)
			( Objects
				( ValidObjects  oAll )
			)
			( Analysis
			)
		)
		( Attribute
			( Name "WACKO" )
			( Description " " )
			( Value
				( DataType ( dString ) )
				( Status  sProperty  sPackage )
			)
			( Objects
				( ValidObjects  oGate  oGateDefn  oBlock  oPart  oDesign  oSystem  oPartDefn )
				( NoInherit
					( oGate oPin )
				)
			)
			( Analysis
			)
		)
		( Attribute
			( Name "BODY_TYPE" )
			( Description " " )
			( Value
				( DataType ( dString ) )
				( Status  sProperty  sPackage )
			)
			( Objects
				( ValidObjects  oGate  oBlock  oPart  oDesign  oSystem  oGateDefn  oPartDefn )
			)
			( Analysis
			)
		)
	)
	( designConstraints
		( ruleChanges
			( allRules )
			( design "p5v_stby"
			)
			( signal "@mstr_symbols.p5v_stby(sch_1):g"
				( objectFlag fObjectAlias )
				( objectStatus "g" )
			)
			( signal "@mstr_symbols.p5v_stby(sch_1):page1_g"
				( objectFlag fObjectAlias )
				( objectStatus "page1_g" )
			)
			( signal "@mstr_symbols.p5v_stby(sch_1):p5v_stby"
				( alias ( signalRef "@mstr_symbols.p5v_stby(sch_1):page1_p5v_stby") )
				( alias ( signalRef "@mstr_symbols.p5v_stby(sch_1):page1_g") )
				( alias ( signalRef "@mstr_symbols.p5v_stby(sch_1):g") )
				( objectStatus "p5v_stby" )
			)
			( signal "@mstr_symbols.p5v_stby(sch_1):page1_p5v_stby"
				( objectFlag fObjectAlias )
				( objectStatus "page1_p5v_stby" )
			)
		)
	)
)
